# SCM (Grand Teton) — schematic netlist excerpt (pin names and nets, part order shuffled) for the footprints in the layout excerpt that follows; sources: Cadence DE-HDL packaged netlist, KiCad conversion of 12092022_DA0F0TMDCD0_F0T_Management_Board_D_brd_V3_OCP.brd

C84  Q_CAP  0.1UF 25V 10% X7R  pkg 0402  page 16 : A = P1V2_AUX ; B = GND
R730  Q_RES  4.7K 1% CHIP  pkg 0402LF  page 29 : A = P3V3_AUX ; B = FM_DEBUG_PORT_R_PRSNT_N

(kicad_pcb
	(version 20260206)
	(generator "pcbnew")
	(generator_version "10.0")
	(general
		(thickness 1.6)
		(legacy_teardrops no)
	)
	(paper "A4")
	(title_block
		(title "12092022_DA0F0TMDCD0_F0T_Management_Board_D_brd_V3_OCP.brd")
		(comment 1 "Grand Teton / footprints 1253-1254 of 1440")
	)
	(layers
		(0 "F.Cu" signal "TOP")
		(4 "In1.Cu" signal "GND")
		(6 "In2.Cu" signal "IN1")
		(8 "In3.Cu" signal "GND1")
		(10 "In4.Cu" signal "IN2")
		(12 "In5.Cu" signal "VCC")
		(14 "In6.Cu" signal "VCC1")
		(16 "In7.Cu" signal "IN3")
		(18 "In8.Cu" signal "GND2")
		(20 "In9.Cu" signal "IN4")
		(22 "In10.Cu" signal "GND3")
		(2 "B.Cu" signal "BOTTOM")
		(9 "F.Adhes" user "F.Adhesive")
		(11 "B.Adhes" user "B.Adhesive")
		(13 "F.Paste" user "Package Geometry/Pastemask Top")
		(15 "B.Paste" user "Package Geometry/Pastemask Bottom")
		(5 "F.SilkS" user "Ref Des/Silkscreen Top")
		(7 "B.SilkS" user "Ref Des/Silkscreen Bottom")
		(1 "F.Mask" user "Board Geometry/Soldermask Top")
		(3 "B.Mask" user "Board Geometry/Soldermask Bottom")
		(17 "Dwgs.User" user "User.Drawings")
		(19 "Cmts.User" user "User.Comments")
		(21 "Eco1.User" user "User.Eco1")
		(23 "Eco2.User" user "User.Eco2")
		(25 "Edge.Cuts" user "Board Geometry/Outline")
		(27 "Margin" user)
		(31 "F.CrtYd" user "Package Geometry/Place Bound Top")
		(29 "B.CrtYd" user "Package Geometry/Place Bound Bottom")
		(35 "F.Fab" user "Ref Des/Assembly Top")
		(33 "B.Fab" user "Ref Des/Assembly Bottom")
	)
	(footprint ""
		(layer "B.Cu")
		(at 59.055 -18.034)
		(property "Reference" "R730"
			(at 0 0 0)
			(layer "B.SilkS")
			(hide yes)
			(effects
				(font
					(size 1.27 1.27)
				)
				(justify mirror)
			)
		)
		(property "Value" ""
			(at 0 0 0)
			(layer "B.Fab")
			(effects
				(font
					(size 1.27 1.27)
				)
				(justify mirror)
			)
		)
		(duplicate_pad_numbers_are_jumpers no)
		(fp_line
			(start -0.7874 -0.4064)
			(end -0.7874 0.4064)
			(stroke
				(width 0.1524)
				(type default)
			)
			(layer "B.SilkS")
		)
		(fp_line
			(start -0.7874 0.4064)
			(end 0.7874 0.4064)
			(stroke
				(width 0.1524)
				(type default)
			)
			(layer "B.SilkS")
		)
		(fp_line
			(start 0.7874 -0.4064)
			(end -0.7874 -0.4064)
			(stroke
				(width 0.1524)
				(type default)
			)
			(layer "B.SilkS")
		)
		(fp_line
			(start 0.7874 0.4064)
			(end 0.7874 -0.4064)
			(stroke
				(width 0.1524)
				(type default)
			)
			(layer "B.SilkS")
		)
		(fp_line
			(start -0.67945 -0.3048)
			(end -0.67945 0.3048)
			(stroke
				(width 0.1)
				(type default)
			)
			(layer "B.Fab")
		)
		(fp_line
			(start -0.67945 0.3048)
			(end -0.120396 0.3048)
			(stroke
				(width 0.1)
				(type default)
			)
			(layer "B.Fab")
		)
		(fp_line
			(start -0.12065 -0.3048)
			(end -0.67945 -0.3048)
			(stroke
				(width 0.1)
				(type default)
			)
			(layer "B.Fab")
		)
		(fp_line
			(start -0.12065 -0.2794)
			(end -0.12065 -0.3048)
			(stroke
				(width 0.1)
				(type default)
			)
			(layer "B.Fab")
		)
		(fp_line
			(start -0.120396 0.2794)
			(end 0.12065 0.2794)
			(stroke
				(width 0.1)
				(type default)
			)
			(layer "B.Fab")
		)
		(fp_line
			(start -0.120396 0.3048)
			(end -0.120396 0.2794)
			(stroke
				(width 0.1)
				(type default)
			)
			(layer "B.Fab")
		)
		(fp_line
			(start 0.12065 -0.305054)
			(end 0.12065 -0.2794)
			(stroke
				(width 0.1)
				(type default)
			)
			(layer "B.Fab")
		)
		(fp_line
			(start 0.12065 -0.2794)
			(end -0.12065 -0.2794)
			(stroke
				(width 0.1)
				(type default)
			)
			(layer "B.Fab")
		)
		(fp_line
			(start 0.12065 0.2794)
			(end 0.12065 0.3048)
			(stroke
				(width 0.1)
				(type default)
			)
			(layer "B.Fab")
		)
		(fp_line
			(start 0.12065 0.3048)
			(end 0.67945 0.3048)
			(stroke
				(width 0.1)
				(type default)
			)
			(layer "B.Fab")
		)
		(fp_line
			(start 0.67945 -0.305054)
			(end 0.12065 -0.305054)
			(stroke
				(width 0.1)
				(type default)
			)
			(layer "B.Fab")
		)
		(fp_line
			(start 0.67945 0.3048)
			(end 0.67945 -0.305054)
			(stroke
				(width 0.1)
				(type default)
			)
			(layer "B.Fab")
		)
		(pad "1" smd circle
			(at 0.40005 0 180)
			(size 0 0)
			(layers "B.Cu" "B.Mask" "B.Paste")
			(net "P3V3_AUX")
		)
		(pad "2" smd circle
			(at -0.40005 0 180)
			(size 0 0)
			(layers "B.Cu" "B.Mask" "B.Paste")
			(net "FM_DEBUG_PORT_R_PRSNT_N")
		)
	)
	(footprint ""
		(layer "B.Cu")
		(at 54.917848 -49.255934 180)
		(property "Reference" "C84"
			(at 0 0 0)
			(layer "B.SilkS")
			(hide yes)
			(effects
				(font
					(size 1.27 1.27)
				)
				(justify mirror)
			)
		)
		(property "Value" ""
			(at 0 0 0)
			(layer "B.Fab")
			(effects
				(font
					(size 1.27 1.27)
				)
				(justify mirror)
			)
		)
		(duplicate_pad_numbers_are_jumpers no)
		(fp_line
			(start 0.7874 0.4064)
			(end 0.7874 -0.4064)
			(stroke
				(width 0.1524)
				(type default)
			)
			(layer "B.SilkS")
		)
		(fp_line
			(start 0.7874 -0.4064)
			(end -0.7874 -0.4064)
			(stroke
				(width 0.1524)
				(type default)
			)
			(layer "B.SilkS")
		)
		(fp_line
			(start -0.7874 0.4064)
			(end 0.7874 0.4064)
			(stroke
				(width 0.1524)
				(type default)
			)
			(layer "B.SilkS")
		)
		(fp_line
			(start -0.7874 -0.4064)
			(end -0.7874 0.4064)
			(stroke
				(width 0.1524)
				(type default)
			)
			(layer "B.SilkS")
		)
		(fp_line
			(start 0.67945 0.3048)
			(end 0.67945 -0.305054)
			(stroke
				(width 0.1)
				(type default)
			)
			(layer "B.Fab")
		)
		(fp_line
			(start 0.67945 -0.305054)
			(end 0.12065 -0.305054)
			(stroke
				(width 0.1)
				(type default)
			)
			(layer "B.Fab")
		)
		(fp_line
			(start 0.12065 0.3048)
			(end 0.67945 0.3048)
			(stroke
				(width 0.1)
				(type default)
			)
			(layer "B.Fab")
		)
		(fp_line
			(start 0.12065 0.2794)
			(end 0.12065 0.3048)
			(stroke
				(width 0.1)
				(type default)
			)
			(layer "B.Fab")
		)
		(fp_line
			(start 0.12065 -0.2794)
			(end -0.12065 -0.2794)
			(stroke
				(width 0.1)
				(type default)
			)
			(layer "B.Fab")
		)
		(fp_line
			(start 0.12065 -0.305054)
			(end 0.12065 -0.2794)
			(stroke
				(width 0.1)
				(type default)
			)
			(layer "B.Fab")
		)
		(fp_line
			(start -0.120396 0.3048)
			(end -0.120396 0.2794)
			(stroke
				(width 0.1)
				(type default)
			)
			(layer "B.Fab")
		)
		(fp_line
			(start -0.120396 0.2794)
			(end 0.12065 0.2794)
			(stroke
				(width 0.1)
				(type default)
			)
			(layer "B.Fab")
		)
		(fp_line
			(start -0.12065 -0.2794)
			(end -0.12065 -0.3048)
			(stroke
				(width 0.1)
				(type default)
			)
			(layer "B.Fab")
		)
		(fp_line
			(start -0.12065 -0.3048)
			(end -0.67945 -0.3048)
			(stroke
				(width 0.1)
				(type default)
			)
			(layer "B.Fab")
		)
		(fp_line
			(start -0.67945 0.3048)
			(end -0.120396 0.3048)
			(stroke
				(width 0.1)
				(type default)
			)
			(layer "B.Fab")
		)
		(fp_line
			(start -0.67945 -0.3048)
			(end -0.67945 0.3048)
			(stroke
				(width 0.1)
				(type default)
			)
			(layer "B.Fab")
		)
		(pad "1" smd circle
			(at 0.40005 0)
			(size 0 0)
			(layers "B.Cu" "B.Mask" "B.Paste")
			(net "P1V2_AUX")
		)
		(pad "2" smd circle
			(at -0.40005 0)
			(size 0 0)
			(layers "B.Cu" "B.Mask" "B.Paste")
			(net "GND")
		)
	)
)
